# T6G (Grand Teton) — schematic netlist excerpt (pin names and nets, part order shuffled) for the footprints in the layout excerpt that follows; sources: Cadence DE-HDL packaged netlist, KiCad conversion of 04192023_DAF0TMB3IC0_F0TG_MB_C_brd_V02_OCP.brd

R218  Q_RES  33 5% CHIP  pkg 0402LF  page 81 : A = CPU0_PWR_GOOD ; B = FM_CPU0_PWR_GOOD
C862  Q_CAP_DIFFBUS  DIFF BUS_0.22UF 6.3V 20% X6S  pkg C0201  page 64 : \1\ = P5E_CPU0_P2_TX_C_DN<3> ; \2\ = P5E_CPU0_P2_TX_DN<3>
R1621  Q_RES  1K 1% CHIP  pkg 0402LF  page 172 : A = PVDD18_S5_P0 ; B = HDT_HDR_TRST_N_R

(kicad_pcb
	(version 20260206)
	(generator "pcbnew")
	(generator_version "10.0")
	(general
		(thickness 1.6)
		(legacy_teardrops no)
	)
	(paper "A4")
	(title_block
		(title "04192023_DAF0TMB3IC0_F0TG_MB_C_brd_V02_OCP.brd")
		(comment 1 "Grand Teton / footprints 4724-4726 of 8354")
	)
	(layers
		(0 "F.Cu" signal "TOP")
		(4 "In1.Cu" signal "GND")
		(6 "In2.Cu" signal "IN1")
		(8 "In3.Cu" signal "GND1")
		(10 "In4.Cu" signal "IN2")
		(12 "In5.Cu" signal "GND2")
		(14 "In6.Cu" signal "IN3")
		(16 "In7.Cu" signal "GND3")
		(18 "In8.Cu" signal "VCC")
		(20 "In9.Cu" signal "VCC1")
		(22 "In10.Cu" signal "GND4")
		(24 "In11.Cu" signal "IN4")
		(26 "In12.Cu" signal "GND5")
		(28 "In13.Cu" signal "IN5")
		(30 "In14.Cu" signal "GND6")
		(32 "In15.Cu" signal "IN6")
		(34 "In16.Cu" signal "GND7")
		(2 "B.Cu" signal "BOTTOM")
		(9 "F.Adhes" user "F.Adhesive")
		(11 "B.Adhes" user "B.Adhesive")
		(13 "F.Paste" user "Package Geometry/Pastemask Top")
		(15 "B.Paste" user "Package Geometry/Pastemask Bottom")
		(5 "F.SilkS" user "Ref Des/Silkscreen Top")
		(7 "B.SilkS" user "Ref Des/Silkscreen Bottom")
		(1 "F.Mask" user "Board Geometry/Soldermask Top")
		(3 "B.Mask" user "Board Geometry/Soldermask Bottom")
		(17 "Dwgs.User" user "User.Drawings")
		(19 "Cmts.User" user "User.Comments")
		(21 "Eco1.User" user "User.Eco1")
		(23 "Eco2.User" user "User.Eco2")
		(25 "Edge.Cuts" user "Board Geometry/Outline")
		(27 "Margin" user)
		(31 "F.CrtYd" user "Package Geometry/Place Bound Top")
		(29 "B.CrtYd" user "Package Geometry/Place Bound Bottom")
		(35 "F.Fab" user "Ref Des/Assembly Top")
		(33 "B.Fab" user "Ref Des/Assembly Bottom")
	)
	(footprint ""
		(layer "F.Cu")
		(at 403.682962 -58.2295 180)
		(property "Reference" "R1621"
			(at 0 0 180)
			(layer "F.SilkS")
			(hide yes)
			(effects
				(font
					(size 1.27 1.27)
				)
			)
		)
		(property "Value" ""
			(at 0 0 180)
			(layer "F.Fab")
			(effects
				(font
					(size 1.27 1.27)
				)
			)
		)
		(duplicate_pad_numbers_are_jumpers no)
		(fp_line
			(start 0.7874 0.4064)
			(end -0.7874 0.4064)
			(stroke
				(width 0.1524)
				(type default)
			)
			(layer "F.SilkS")
		)
		(fp_line
			(start 0.7874 -0.4064)
			(end 0.7874 0.4064)
			(stroke
				(width 0.1524)
				(type default)
			)
			(layer "F.SilkS")
		)
		(fp_line
			(start -0.7874 0.4064)
			(end -0.7874 -0.4064)
			(stroke
				(width 0.1524)
				(type default)
			)
			(layer "F.SilkS")
		)
		(fp_line
			(start -0.7874 -0.4064)
			(end 0.7874 -0.4064)
			(stroke
				(width 0.1524)
				(type default)
			)
			(layer "F.SilkS")
		)
		(fp_line
			(start 0.67945 0.3048)
			(end 0.120396 0.3048)
			(stroke
				(width 0.1)
				(type default)
			)
			(layer "F.Fab")
		)
		(fp_line
			(start 0.67945 -0.3048)
			(end 0.67945 0.3048)
			(stroke
				(width 0.1)
				(type default)
			)
			(layer "F.Fab")
		)
		(fp_line
			(start 0.12065 -0.2794)
			(end 0.12065 -0.3048)
			(stroke
				(width 0.1)
				(type default)
			)
			(layer "F.Fab")
		)
		(fp_line
			(start 0.12065 -0.3048)
			(end 0.67945 -0.3048)
			(stroke
				(width 0.1)
				(type default)
			)
			(layer "F.Fab")
		)
		(fp_line
			(start 0.120396 0.3048)
			(end 0.120396 0.2794)
			(stroke
				(width 0.1)
				(type default)
			)
			(layer "F.Fab")
		)
		(fp_line
			(start 0.120396 0.2794)
			(end -0.12065 0.2794)
			(stroke
				(width 0.1)
				(type default)
			)
			(layer "F.Fab")
		)
		(fp_line
			(start -0.12065 0.3048)
			(end -0.67945 0.3048)
			(stroke
				(width 0.1)
				(type default)
			)
			(layer "F.Fab")
		)
		(fp_line
			(start -0.12065 0.2794)
			(end -0.12065 0.3048)
			(stroke
				(width 0.1)
				(type default)
			)
			(layer "F.Fab")
		)
		(fp_line
			(start -0.12065 -0.2794)
			(end 0.12065 -0.2794)
			(stroke
				(width 0.1)
				(type default)
			)
			(layer "F.Fab")
		)
		(fp_line
			(start -0.12065 -0.305054)
			(end -0.12065 -0.2794)
			(stroke
				(width 0.1)
				(type default)
			)
			(layer "F.Fab")
		)
		(fp_line
			(start -0.67945 0.3048)
			(end -0.67945 -0.305054)
			(stroke
				(width 0.1)
				(type default)
			)
			(layer "F.Fab")
		)
		(fp_line
			(start -0.67945 -0.305054)
			(end -0.12065 -0.305054)
			(stroke
				(width 0.1)
				(type default)
			)
			(layer "F.Fab")
		)
		(pad "1" smd circle
			(at -0.40005 0 180)
			(size 0 0)
			(layers "F.Cu" "F.Mask" "F.Paste")
			(net "PVDD18_S5_P0")
		)
		(pad "2" smd circle
			(at 0.40005 0 180)
			(size 0 0)
			(layers "F.Cu" "F.Mask" "F.Paste")
			(net "HDT_HDR_TRST_N_R")
		)
	)
	(footprint ""
		(layer "F.Cu")
		(at 200.939908 -112.609376 180)
		(property "Reference" "R218"
			(at 0 0 180)
			(layer "F.SilkS")
			(hide yes)
			(effects
				(font
					(size 1.27 1.27)
				)
			)
		)
		(property "Value" ""
			(at 0 0 180)
			(layer "F.Fab")
			(effects
				(font
					(size 1.27 1.27)
				)
			)
		)
		(duplicate_pad_numbers_are_jumpers no)
		(fp_line
			(start 0.7874 0.4064)
			(end -0.7874 0.4064)
			(stroke
				(width 0.1524)
				(type default)
			)
			(layer "F.SilkS")
		)
		(fp_line
			(start 0.7874 -0.4064)
			(end 0.7874 0.4064)
			(stroke
				(width 0.1524)
				(type default)
			)
			(layer "F.SilkS")
		)
		(fp_line
			(start -0.7874 0.4064)
			(end -0.7874 -0.4064)
			(stroke
				(width 0.1524)
				(type default)
			)
			(layer "F.SilkS")
		)
		(fp_line
			(start -0.7874 -0.4064)
			(end 0.7874 -0.4064)
			(stroke
				(width 0.1524)
				(type default)
			)
			(layer "F.SilkS")
		)
		(fp_line
			(start 0.67945 0.3048)
			(end 0.120396 0.3048)
			(stroke
				(width 0.1)
				(type default)
			)
			(layer "F.Fab")
		)
		(fp_line
			(start 0.67945 -0.3048)
			(end 0.67945 0.3048)
			(stroke
				(width 0.1)
				(type default)
			)
			(layer "F.Fab")
		)
		(fp_line
			(start 0.12065 -0.2794)
			(end 0.12065 -0.3048)
			(stroke
				(width 0.1)
				(type default)
			)
			(layer "F.Fab")
		)
		(fp_line
			(start 0.12065 -0.3048)
			(end 0.67945 -0.3048)
			(stroke
				(width 0.1)
				(type default)
			)
			(layer "F.Fab")
		)
		(fp_line
			(start 0.120396 0.3048)
			(end 0.120396 0.2794)
			(stroke
				(width 0.1)
				(type default)
			)
			(layer "F.Fab")
		)
		(fp_line
			(start 0.120396 0.2794)
			(end -0.12065 0.2794)
			(stroke
				(width 0.1)
				(type default)
			)
			(layer "F.Fab")
		)
		(fp_line
			(start -0.12065 0.3048)
			(end -0.67945 0.3048)
			(stroke
				(width 0.1)
				(type default)
			)
			(layer "F.Fab")
		)
		(fp_line
			(start -0.12065 0.2794)
			(end -0.12065 0.3048)
			(stroke
				(width 0.1)
				(type default)
			)
			(layer "F.Fab")
		)
		(fp_line
			(start -0.12065 -0.2794)
			(end 0.12065 -0.2794)
			(stroke
				(width 0.1)
				(type default)
			)
			(layer "F.Fab")
		)
		(fp_line
			(start -0.12065 -0.305054)
			(end -0.12065 -0.2794)
			(stroke
				(width 0.1)
				(type default)
			)
			(layer "F.Fab")
		)
		(fp_line
			(start -0.67945 0.3048)
			(end -0.67945 -0.305054)
			(stroke
				(width 0.1)
				(type default)
			)
			(layer "F.Fab")
		)
		(fp_line
			(start -0.67945 -0.305054)
			(end -0.12065 -0.305054)
			(stroke
				(width 0.1)
				(type default)
			)
			(layer "F.Fab")
		)
		(pad "1" smd circle
			(at -0.40005 0 180)
			(size 0 0)
			(layers "F.Cu" "F.Mask" "F.Paste")
			(net "CPU0_PWR_GOOD")
		)
		(pad "2" smd circle
			(at 0.40005 0 180)
			(size 0 0)
			(layers "F.Cu" "F.Mask" "F.Paste")
			(net "FM_CPU0_PWR_GOOD")
		)
	)
	(footprint ""
		(layer "F.Cu")
		(at 401.23364 -378.95403 -90)
		(property "Reference" "C862"
			(at 0 0 270)
			(layer "F.SilkS")
			(hide yes)
			(effects
				(font
					(size 1.27 1.27)
				)
			)
		)
		(property "Value" ""
			(at 0 0 270)
			(layer "F.Fab")
			(effects
				(font
					(size 1.27 1.27)
				)
			)
		)
		(duplicate_pad_numbers_are_jumpers no)
		(fp_line
			(start -0.299974 0.150114)
			(end -0.299974 -0.150114)
			(stroke
				(width 0.1)
				(type default)
			)
			(layer "F.Fab")
		)
		(fp_line
			(start 0.299974 0.150114)
			(end -0.299974 0.150114)
			(stroke
				(width 0.1)
				(type default)
			)
			(layer "F.Fab")
		)
		(fp_line
			(start -0.299974 -0.150114)
			(end 0.299974 -0.150114)
			(stroke
				(width 0.1)
				(type default)
			)
			(layer "F.Fab")
		)
		(fp_line
			(start 0.299974 -0.150114)
			(end 0.299974 0.150114)
			(stroke
				(width 0.1)
				(type default)
			)
			(layer "F.Fab")
		)
		(pad "1" smd rect
			(at -0.2667 0 270)
			(size 0.3048 0.381)
			(layers "F.Cu" "F.Mask" "F.Paste")
			(net "P5E_CPU0_P2_TX_C_DN<3>")
		)
		(pad "2" smd rect
			(at 0.2667 0 270)
			(size 0.3048 0.381)
			(layers "F.Cu" "F.Mask" "F.Paste")
			(net "P5E_CPU0_P2_TX_DN<3>")
		)
	)
)
